(kicad_pcb
	(version 20241229)
	(generator "pcbnew")
	(generator_version "9.0")
	(general
		(thickness 1.711)
		(legacy_teardrops no)
	)
	(paper "A4")
	(title_block
		(title "Antmicro Baseboard for Jetson AGX Thor")
		(date "2026-02-18")
		(rev "1.1.0")
		(company "Antmicro Ltd")
		(comment 1 "www.antmicro.com")
		(comment 9 "footprints 115-120 of 1170")
	)
	(layers
		(0 "F.Cu" signal)
		(4 "In1.Cu" signal)
		(6 "In2.Cu" signal)
		(8 "In3.Cu" signal)
		(10 "In4.Cu" jumper)
		(12 "In5.Cu" signal)
		(14 "In6.Cu" signal)
		(16 "In7.Cu" signal)
		(18 "In8.Cu" signal)
		(2 "B.Cu" signal)
		(9 "F.Adhes" user "F.Adhesive")
		(11 "B.Adhes" user "B.Adhesive")
		(13 "F.Paste" user)
		(15 "B.Paste" user)
		(5 "F.SilkS" user "F.Silkscreen")
		(7 "B.SilkS" user "B.Silkscreen")
		(1 "F.Mask" user)
		(3 "B.Mask" user)
		(17 "Dwgs.User" user "User.Drawings")
		(19 "Cmts.User" user "User.Comments")
		(21 "Eco1.User" user "User.Eco1")
		(23 "Eco2.User" user "User.Eco2")
		(25 "Edge.Cuts" user)
		(27 "Margin" user)
		(31 "F.CrtYd" user "F.Courtyard")
		(29 "B.CrtYd" user "B.Courtyard")
		(35 "F.Fab" user)
		(33 "B.Fab" user)
	)
	(footprint "antmicro-footprints:C_0402_1005Metric"
		(layer "F.Cu")
		(at 109.8 128.5)
		(descr "Capacitor SMD 0402")
		(tags "capacitor SMD 0402")
		(property "Reference" "C196"
			(at -0.9 -0.4 180)
			(layer "F.SilkS")
			(effects
				(font
					(size 0.7 0.7)
					(thickness 0.15)
				)
				(justify right top)
			)
		)
		(property "Value" "C_220n_0402"
			(at -1.022927 2.155213 180)
			(layer "F.Fab")
			(effects
				(font
					(size 0.7 0.7)
					(thickness 0.15)
				)
				(justify right top)
			)
		)
		(property "Datasheet" "https://www.yageo.com/en/Chart/Download/pdf/CC0402KRX5R6BB224"
			(at 0 0 180)
			(layer "F.Fab")
			(hide yes)
			(effects
				(font
					(size 1.27 1.27)
					(thickness 0.15)
				)
			)
		)
		(property "Description" "SMD Multilayer Ceramic Capacitor, 0.22 µF, 10 V, 0402 [1005 Metric], ± 10%, X5R, CC Series"
			(at 0 0 180)
			(layer "F.Fab")
			(hide yes)
			(effects
				(font
					(size 1.27 1.27)
					(thickness 0.15)
				)
			)
		)
		(property "MPN" "CC0402KRX5R6BB224"
			(at 0 0 180)
			(unlocked yes)
			(layer "F.Fab")
			(hide yes)
			(effects
				(font
					(size 1 1)
					(thickness 0.15)
				)
			)
		)
		(property "Val" "220n"
			(at 0 0 180)
			(unlocked yes)
			(layer "F.Fab")
			(hide yes)
			(effects
				(font
					(size 1 1)
					(thickness 0.15)
				)
			)
		)
		(property "Voltage" "25V"
			(at 0 0 180)
			(unlocked yes)
			(layer "F.Fab")
			(hide yes)
			(effects
				(font
					(size 1 1)
					(thickness 0.15)
				)
			)
		)
		(property "Dielectric" "X7R"
			(at 0 0 180)
			(unlocked yes)
			(layer "F.Fab")
			(hide yes)
			(effects
				(font
					(size 1 1)
					(thickness 0.15)
				)
			)
		)
		(property "Manufacturer" "YAGEO"
			(at 0 0 180)
			(unlocked yes)
			(layer "F.Fab")
			(hide yes)
			(effects
				(font
					(size 1 1)
					(thickness 0.15)
				)
			)
		)
		(property "License" "Apache-2.0"
			(at 0 0 180)
			(unlocked yes)
			(layer "F.Fab")
			(hide yes)
			(effects
				(font
					(size 1 1)
					(thickness 0.15)
				)
			)
		)
		(property "Author" "Antmicro"
			(at 0 0 180)
			(unlocked yes)
			(layer "F.Fab")
			(hide yes)
			(effects
				(font
					(size 1 1)
					(thickness 0.15)
				)
			)
		)
		(property "Public" "False"
			(at 0 0 180)
			(unlocked yes)
			(layer "F.Fab")
			(hide yes)
			(effects
				(font
					(size 1 1)
					(thickness 0.15)
				)
			)
		)
		(sheetname "/M.2/")
		(sheetfile "m2.kicad_sch")
		(attr smd)
		(fp_poly
			(pts
				(xy -0.925 -0.47) (xy -0.925 0.47) (xy 0.925 0.47) (xy 0.925 -0.47)
			)
			(stroke
				(width 0.05)
				(type default)
			)
			(fill no)
			(layer "F.CrtYd")
		)
		(fp_line
			(start -0.494 -0.25)
			(end 0.504 -0.25)
			(stroke
				(width 0.15)
				(type solid)
			)
			(layer "F.Fab")
		)
		(fp_line
			(start -0.494 0.248)
			(end -0.494 -0.25)
			(stroke
				(width 0.15)
				(type solid)
			)
			(layer "F.Fab")
		)
		(fp_line
			(start 0.504 -0.25)
			(end 0.504 0.248)
			(stroke
				(width 0.15)
				(type solid)
			)
			(layer "F.Fab")
		)
		(fp_line
			(start 0.504 0.248)
			(end -0.494 0.248)
			(stroke
				(width 0.15)
				(type solid)
			)
			(layer "F.Fab")
		)
		(fp_text user "${REFERENCE}"
			(at -0.939 4.599 180)
			(layer "F.Fab")
			(effects
				(font
					(size 0.7 0.7)
					(thickness 0.15)
				)
				(justify right top)
			)
		)
		(fp_text user "License: Apache-2.0"
			(at -0.939 5.799 180)
			(layer "F.Fab")
			(effects
				(font
					(size 0.7 0.7)
					(thickness 0.15)
				)
				(justify right top)
			)
		)
		(fp_text user "Author: Antmicro"
			(at -0.939 3.399 180)
			(layer "F.Fab")
			(effects
				(font
					(size 0.7 0.7)
					(thickness 0.15)
				)
				(justify right top)
			)
		)
		(pad "1" smd roundrect
			(at -0.48 0)
			(size 0.59 0.64)
			(layers "F.Cu" "F.Mask" "F.Paste")
			(roundrect_rratio 0.25)
			(net 16 "/M.2/PCIe_{C1x1}.TX0-")
			(pintype "passive")
		)
		(pad "2" smd roundrect
			(at 0.48 0)
			(size 0.59 0.64)
			(layers "F.Cu" "F.Mask" "F.Paste")
			(roundrect_rratio 0.25)
			(net 444 "/M.2/M2_E_PET0_N")
			(pintype "passive")
		)
	)
	(footprint "antmicro-footprints:R_0402_1005Metric"
		(layer "F.Cu")
		(at 195.1 131.3)
		(descr "Resistor SMD 0402")
		(tags "resistor SMD 0402")
		(property "Reference" "R71"
			(at -1.1 5.3 0)
			(layer "F.SilkS")
			(effects
				(font
					(size 0.7 0.7)
					(thickness 0.15)
				)
				(justify left bottom)
			)
		)
		(property "Value" "R_0R_0402"
			(at -1.011843 1.772046 0)
			(layer "F.Fab")
			(effects
				(font
					(size 0.7 0.7)
					(thickness 0.15)
				)
				(justify left bottom)
			)
		)
		(property "Datasheet" "https://industrial.panasonic.com/cdbs/www-data/pdf/RDA0000/AOA0000C301.pdf"
			(at 0 0 0)
			(layer "F.Fab")
			(hide yes)
			(effects
				(font
					(size 1.27 1.27)
					(thickness 0.15)
				)
			)
		)
		(property "Description" "SMD Chip Resistor, Jumper, 0 ohm, 100 mW, 0402 [1005 Metric], Thick Film, General Purpose"
			(at 0 0 0)
			(layer "F.Fab")
			(hide yes)
			(effects
				(font
					(size 1.27 1.27)
					(thickness 0.15)
				)
			)
		)
		(property "MPN" "ERJ2GE0R00X"
			(at 0 0 0)
			(unlocked yes)
			(layer "F.Fab")
			(hide yes)
			(effects
				(font
					(size 1 1)
					(thickness 0.15)
				)
			)
		)
		(property "Manufacturer" "Panasonic"
			(at 0 0 0)
			(unlocked yes)
			(layer "F.Fab")
			(hide yes)
			(effects
				(font
					(size 1 1)
					(thickness 0.15)
				)
			)
		)
		(property "License" "Apache-2.0"
			(at 0 0 0)
			(unlocked yes)
			(layer "F.Fab")
			(hide yes)
			(effects
				(font
					(size 1 1)
					(thickness 0.15)
				)
			)
		)
		(property "Author" "Antmicro"
			(at 0 0 0)
			(unlocked yes)
			(layer "F.Fab")
			(hide yes)
			(effects
				(font
					(size 1 1)
					(thickness 0.15)
				)
			)
		)
		(property "Val" "0R"
			(at 0 0 0)
			(unlocked yes)
			(layer "F.Fab")
			(hide yes)
			(effects
				(font
					(size 1 1)
					(thickness 0.15)
				)
			)
		)
		(property "Tolerance" "~"
			(at 0 0 0)
			(unlocked yes)
			(layer "F.Fab")
			(hide yes)
			(effects
				(font
					(size 1 1)
					(thickness 0.15)
				)
			)
		)
		(property "Current" "1A"
			(at 0 0 180)
			(unlocked yes)
			(layer "F.Fab")
			(hide yes)
			(effects
				(font
					(size 1 1)
					(thickness 0.15)
				)
			)
		)
		(sheetname "/USB Hub/")
		(sheetfile "usb_hub.kicad_sch")
		(attr smd exclude_from_pos_files exclude_from_bom dnp)
		(fp_poly
			(pts
				(xy -0.925 -0.47) (xy -0.925 0.47) (xy 0.925 0.47) (xy 0.925 -0.47)
			)
			(stroke
				(width 0.05)
				(type default)
			)
			(fill no)
			(layer "F.CrtYd")
		)
		(fp_poly
			(pts
				(xy -0.5 -0.25) (xy -0.5 0.25) (xy 0.5 0.25) (xy 0.5 -0.25)
			)
			(stroke
				(width 0.15)
				(type solid)
			)
			(fill no)
			(layer "F.Fab")
		)
		(fp_text user "${REFERENCE}"
			(at -0.95 3.168 0)
			(layer "F.Fab")
			(effects
				(font
					(size 0.7 0.7)
					(thickness 0.15)
				)
				(justify left bottom)
			)
		)
		(fp_text user "Author: Antmicro"
			(at -0.95 4.169 0)
			(layer "F.Fab")
			(effects
				(font
					(size 0.7 0.7)
					(thickness 0.15)
				)
				(justify left bottom)
			)
		)
		(fp_text user "License: Apache-2.0"
			(at -0.949999 5.169 0)
			(layer "F.Fab")
			(effects
				(font
					(size 0.7 0.7)
					(thickness 0.15)
				)
				(justify left bottom)
			)
		)
		(pad "1" smd roundrect
			(at -0.48 0)
			(size 0.59 0.64)
			(layers "F.Cu" "F.Mask" "F.Paste")
			(roundrect_rratio 0.25)
			(net 853 "/I2C_{SYS}.SCL")
			(pintype "passive")
		)
		(pad "2" smd roundrect
			(at 0.48 0)
			(size 0.59 0.64)
			(layers "F.Cu" "F.Mask" "F.Paste")
			(roundrect_rratio 0.25)
			(net 1234 "Net-(U21-PF26)")
			(pintype "passive")
		)
	)
	(footprint "antmicro-footprints:TP_SMD_0.75mm"
		(layer "F.Cu")
		(at 205.8 76.8)
		(property "Reference" "TP77"
			(at 0.5 -0.6 90)
			(layer "F.SilkS")
			(effects
				(font
					(size 0.7 0.7)
					(thickness 0.15)
				)
				(justify left bottom)
			)
		)
		(property "Value" "TP_0.75mm_SMD"
			(at 0 1.2 0)
			(layer "F.Fab")
			(effects
				(font
					(size 0.7 0.7)
					(thickness 0.15)
				)
				(justify left bottom)
			)
		)
		(property "Description" "SMT test point"
			(at 0 0 0)
			(layer "F.Fab")
			(hide yes)
			(effects
				(font
					(size 1.27 1.27)
					(thickness 0.15)
				)
			)
		)
		(property "MPN" ""
			(at 0 0 0)
			(unlocked yes)
			(layer "F.Fab")
			(hide yes)
			(effects
				(font
					(size 1 1)
					(thickness 0.15)
				)
			)
		)
		(property "Manufacturer" ""
			(at 0 0 0)
			(unlocked yes)
			(layer "F.Fab")
			(hide yes)
			(effects
				(font
					(size 1 1)
					(thickness 0.15)
				)
			)
		)
		(property "Author" "Antmicro"
			(at 0 0 0)
			(unlocked yes)
			(layer "F.Fab")
			(hide yes)
			(effects
				(font
					(size 1 1)
					(thickness 0.15)
				)
			)
		)
		(property "License" "Apache-2.0"
			(at 0 0 0)
			(unlocked yes)
			(layer "F.Fab")
			(hide yes)
			(effects
				(font
					(size 1 1)
					(thickness 0.15)
				)
			)
		)
		(sheetname "/Power/")
		(sheetfile "power.kicad_sch")
		(attr exclude_from_pos_files exclude_from_bom)
		(fp_circle
			(center 0 0)
			(end 0.475 0)
			(stroke
				(width 0.05)
				(type default)
			)
			(fill no)
			(layer "F.CrtYd")
		)
		(fp_text user "Author: Antmicro"
			(at -0.4 3.901 0)
			(layer "F.Fab")
			(effects
				(font
					(size 0.7 0.7)
					(thickness 0.15)
				)
				(justify left bottom)
			)
		)
		(fp_text user "License: Apache-2.0"
			(at -0.4 5.101 0)
			(layer "F.Fab")
			(effects
				(font
					(size 0.7 0.7)
					(thickness 0.15)
				)
				(justify left bottom)
			)
		)
		(fp_text user "${REFERENCE}"
			(at -0.4 2.7 0)
			(layer "F.Fab")
			(effects
				(font
					(size 0.7 0.7)
					(thickness 0.15)
				)
				(justify left bottom)
			)
		)
		(pad "1" smd circle
			(at 0 0)
			(size 0.75 0.75)
			(layers "F.Cu" "F.Mask")
			(net 525 "/Power/USBPD2_HV")
			(pinfunction "1")
			(pintype "passive")
		)
	)
	(footprint "antmicro-footprints:R_0402_1005Metric"
		(layer "F.Cu")
		(at 88 62.5 180)
		(descr "Resistor SMD 0402")
		(tags "resistor SMD 0402")
		(property "Reference" "R19"
			(at 17 -8.75 0)
			(layer "F.SilkS")
			(effects
				(font
					(size 0.7 0.7)
					(thickness 0.15)
				)
				(justify right top)
			)
		)
		(property "Value" "R_499k_0402"
			(at -1.011843 1.772047 0)
			(layer "F.Fab")
			(effects
				(font
					(size 0.7 0.7)
					(thickness 0.15)
				)
				(justify right top)
			)
		)
		(property "Datasheet" "https://www.mouser.com/datasheet/2/54/cr-1858361.pdf"
			(at 0 0 0)
			(layer "F.Fab")
			(hide yes)
			(effects
				(font
					(size 1.27 1.27)
					(thickness 0.15)
				)
			)
		)
		(property "Description" "SMD Chip Resistor, 499 kohm, ± 1%, 63 mW, 0402 [1005 Metric], Thick Film, General Purpose"
			(at 0 0 0)
			(layer "F.Fab")
			(hide yes)
			(effects
				(font
					(size 1.27 1.27)
					(thickness 0.15)
				)
			)
		)
		(property "MPN" "CR0402-FX-4993GLF"
			(at 0 0 180)
			(unlocked yes)
			(layer "F.Fab")
			(hide yes)
			(effects
				(font
					(size 1 1)
					(thickness 0.15)
				)
			)
		)
		(property "Manufacturer" "Bourns"
			(at 0 0 180)
			(unlocked yes)
			(layer "F.Fab")
			(hide yes)
			(effects
				(font
					(size 1 1)
					(thickness 0.15)
				)
			)
		)
		(property "License" "Apache-2.0"
			(at 0 0 180)
			(unlocked yes)
			(layer "F.Fab")
			(hide yes)
			(effects
				(font
					(size 1 1)
					(thickness 0.15)
				)
			)
		)
		(property "Author" "Antmicro"
			(at 0 0 180)
			(unlocked yes)
			(layer "F.Fab")
			(hide yes)
			(effects
				(font
					(size 1 1)
					(thickness 0.15)
				)
			)
		)
		(property "Val" "499k"
			(at 0 0 180)
			(unlocked yes)
			(layer "F.Fab")
			(hide yes)
			(effects
				(font
					(size 1 1)
					(thickness 0.15)
				)
			)
		)
		(property "Tolerance" "1%"
			(at 0 0 180)
			(unlocked yes)
			(layer "F.Fab")
			(hide yes)
			(effects
				(font
					(size 1 1)
					(thickness 0.15)
				)
			)
		)
		(sheetname "/SoM_Power/")
		(sheetfile "som_power.kicad_sch")
		(attr smd)
		(fp_rect
			(start -0.925 -0.47)
			(end 0.925 0.47)
			(stroke
				(width 0.05)
				(type default)
			)
			(fill no)
			(layer "F.CrtYd")
		)
		(fp_rect
			(start -0.5 -0.25)
			(end 0.5 0.25)
			(stroke
				(width 0.15)
				(type solid)
			)
			(fill no)
			(layer "F.Fab")
		)
		(fp_text user "${REFERENCE}"
			(at -0.95 3.168 0)
			(layer "F.Fab")
			(effects
				(font
					(size 0.7 0.7)
					(thickness 0.15)
				)
				(justify right top)
			)
		)
		(fp_text user "Author: Antmicro"
			(at -0.95 4.169 0)
			(layer "F.Fab")
			(effects
				(font
					(size 0.7 0.7)
					(thickness 0.15)
				)
				(justify right top)
			)
		)
		(fp_text user "License: Apache-2.0"
			(at -0.95 5.169 0)
			(layer "F.Fab")
			(effects
				(font
					(size 0.7 0.7)
					(thickness 0.15)
				)
				(justify right top)
			)
		)
		(pad "1" smd roundrect
			(at -0.48 0 180)
			(size 0.59 0.64)
			(layers "F.Cu" "F.Mask" "F.Paste")
			(roundrect_rratio 0.25)
			(net 246 "/SoM_Power/~{VDDIN_PWR_BAD}")
			(pintype "passive")
		)
		(pad "2" smd roundrect
			(at 0.48 0 180)
			(size 0.59 0.64)
			(layers "F.Cu" "F.Mask" "F.Paste")
			(roundrect_rratio 0.25)
			(net 213 "+5V_SOM")
			(pintype "passive")
		)
	)
	(footprint "antmicro-footprints:C_0402_1005Metric"
		(layer "F.Cu")
		(at 211.8 103.325 180)
		(descr "Capacitor SMD 0402")
		(tags "capacitor SMD 0402")
		(property "Reference" "C117"
			(at 0.94 0.415 0)
			(layer "F.SilkS")
			(effects
				(font
					(size 0.7 0.7)
					(thickness 0.15)
				)
				(justify right top)
			)
		)
		(property "Value" "C_100n_0402"
			(at -1.022927 2.155213 0)
			(layer "F.Fab")
			(effects
				(font
					(size 0.7 0.7)
					(thickness 0.15)
				)
				(justify right top)
			)
		)
		(property "Datasheet" "https://www.murata.com/products/productdetail?partno=GRM155R61H104KE14%23"
			(at 0 0 0)
			(layer "F.Fab")
			(hide yes)
			(effects
				(font
					(size 1.27 1.27)
					(thickness 0.15)
				)
			)
		)
		(property "Description" "SMD Multilayer Ceramic Capacitor, 0.1 µF, 50 V, 0402 [1005 Metric], ± 10%, X5R, GRM Series"
			(at 0 0 0)
			(layer "F.Fab")
			(hide yes)
			(effects
				(font
					(size 1.27 1.27)
					(thickness 0.15)
				)
			)
		)
		(property "Manufacturer" "Murata"
			(at 0 0 180)
			(unlocked yes)
			(layer "F.Fab")
			(hide yes)
			(effects
				(font
					(size 1 1)
					(thickness 0.15)
				)
			)
		)
		(property "MPN" "GRM155R61H104KE14D"
			(at 0 0 180)
			(unlocked yes)
			(layer "F.Fab")
			(hide yes)
			(effects
				(font
					(size 1 1)
					(thickness 0.15)
				)
			)
		)
		(property "Val" "100n"
			(at 0 0 180)
			(unlocked yes)
			(layer "F.Fab")
			(hide yes)
			(effects
				(font
					(size 1 1)
					(thickness 0.15)
				)
			)
		)
		(property "License" "Apache-2.0"
			(at 0 0 180)
			(unlocked yes)
			(layer "F.Fab")
			(hide yes)
			(effects
				(font
					(size 1 1)
					(thickness 0.15)
				)
			)
		)
		(property "Author" "Antmicro"
			(at 0 0 180)
			(unlocked yes)
			(layer "F.Fab")
			(hide yes)
			(effects
				(font
					(size 1 1)
					(thickness 0.15)
				)
			)
		)
		(property "Voltage" "50V"
			(at 0 0 180)
			(unlocked yes)
			(layer "F.Fab")
			(hide yes)
			(effects
				(font
					(size 1 1)
					(thickness 0.15)
				)
			)
		)
		(property "Dielectric" "X5R"
			(at 0 0 180)
			(unlocked yes)
			(layer "F.Fab")
			(hide yes)
			(effects
				(font
					(size 1 1)
					(thickness 0.15)
				)
			)
		)
		(sheetname "/Recovery USB/")
		(sheetfile "recovery_usb.kicad_sch")
		(attr smd)
		(fp_rect
			(start -0.925 -0.47)
			(end 0.925 0.47)
			(stroke
				(width 0.05)
				(type default)
			)
			(fill no)
			(layer "F.CrtYd")
		)
		(fp_line
			(start 0.504 0.248)
			(end -0.494 0.248)
			(stroke
				(width 0.15)
				(type solid)
			)
			(layer "F.Fab")
		)
		(fp_line
			(start 0.504 -0.25)
			(end 0.504 0.248)
			(stroke
				(width 0.15)
				(type solid)
			)
			(layer "F.Fab")
		)
		(fp_line
			(start -0.494 0.248)
			(end -0.494 -0.25)
			(stroke
				(width 0.15)
				(type solid)
			)
			(layer "F.Fab")
		)
		(fp_line
			(start -0.494 -0.25)
			(end 0.504 -0.25)
			(stroke
				(width 0.15)
				(type solid)
			)
			(layer "F.Fab")
		)
		(fp_text user "${REFERENCE}"
			(at -0.939 4.599 0)
			(layer "F.Fab")
			(effects
				(font
					(size 0.7 0.7)
					(thickness 0.15)
				)
				(justify right top)
			)
		)
		(fp_text user "Author: Antmicro"
			(at -0.939 3.399 0)
			(layer "F.Fab")
			(effects
				(font
					(size 0.7 0.7)
					(thickness 0.15)
				)
				(justify right top)
			)
		)
		(fp_text user "License: Apache-2.0"
			(at -0.939 5.799 0)
			(layer "F.Fab")
			(effects
				(font
					(size 0.7 0.7)
					(thickness 0.15)
				)
				(justify right top)
			)
		)
		(pad "1" smd roundrect
			(at -0.48 0 180)
			(size 0.59 0.64)
			(layers "F.Cu" "F.Mask" "F.Paste")
			(roundrect_rratio 0.25)
			(net 2 "+3V3")
			(pintype "passive")
		)
		(pad "2" smd roundrect
			(at 0.48 0 180)
			(size 0.59 0.64)
			(layers "F.Cu" "F.Mask" "F.Paste")
			(roundrect_rratio 0.25)
			(net 1 "GND")
			(pintype "passive")
		)
	)
	(footprint "antmicro-footprints:Fiducial_1mm_Mask3mm"
		(layer "F.Cu")
		(at 61.67 70.35)
		(descr "Circular Fiducial, 1.5mm bare copper, 3mm soldermask opening")
		(tags "fiducial")
		(property "Reference" "FD1"
			(at -1.03 2.5 0)
			(layer "F.SilkS")
			(effects
				(font
					(size 0.7 0.7)
					(thickness 0.15)
				)
				(justify left bottom)
			)
		)
		(property "Value" "Fiducial_1mm_Mask3mm"
			(at 0 2.603 0)
			(layer "F.Fab")
			(effects
				(font
					(size 0.7 0.7)
					(thickness 0.15)
				)
				(justify left bottom)
			)
		)
		(property "Description" "Fiducial mask"
			(at 0 0 0)
			(layer "F.Fab")
			(hide yes)
			(effects
				(font
					(size 1.27 1.27)
					(thickness 0.15)
				)
			)
		)
		(property "Author" "Antmicro"
			(at 0 0 0)
			(unlocked yes)
			(layer "F.Fab")
			(hide yes)
			(effects
				(font
					(size 1 1)
					(thickness 0.15)
				)
			)
		)
		(property "License" "Apache-2.0"
			(at 0 0 0)
			(unlocked yes)
			(layer "F.Fab")
			(hide yes)
			(effects
				(font
					(size 1 1)
					(thickness 0.15)
				)
			)
		)
		(sheetname "/")
		(sheetfile "jetson-agx-thor-baseboard.kicad_sch")
		(attr exclude_from_pos_files exclude_from_bom)
		(fp_circle
			(center 0 0)
			(end 1.5 0)
			(stroke
				(width 0.05)
				(type solid)
			)
			(fill no)
			(layer "F.CrtYd")
		)
		(fp_circle
			(center 0 0)
			(end 1.5 0)
			(stroke
				(width 0.15)
				(type solid)
			)
			(fill no)
			(layer "F.Fab")
		)
		(fp_text user "${REFERENCE}"
			(at -1.25 4.603 0)
			(layer "F.Fab")
			(effects
				(font
					(size 0.7 0.7)
					(thickness 0.15)
				)
				(justify left bottom)
			)
		)
		(fp_text user "License: Apache-2.0"
			(at -1.25 7.003 0)
			(layer "F.Fab")
			(effects
				(font
					(size 0.7 0.7)
					(thickness 0.15)
				)
				(justify left bottom)
			)
		)
		(fp_text user "Author: Antmicro"
			(at -1.25 5.803 0)
			(layer "F.Fab")
			(effects
				(font
					(size 0.7 0.7)
					(thickness 0.15)
				)
				(justify left bottom)
			)
		)
		(pad "" smd circle
			(at 0 0)
			(size 1 1)
			(layers "F.Cu" "F.Mask")
			(solder_mask_margin 1)
			(clearance 1)
		)
	)
)
